# S9S_MB_2U (Grand Teton) — schematic netlist excerpt (pin names and nets, part order shuffled) for the footprints in the layout excerpt that follows; sources: Cadence DE-HDL packaged netlist, KiCad conversion of 03242023_DA0F0TMBIJ0_F0T_Motherboard_J_brd_V01_OCP.brd

Y4  Q_XTAL_4P_13BI_24GND  12MHZ MISC  pkg OSC4_DNCA250000ETS_2-5X2_H26  page 152
  X1  = USB_HUB_XTAL_IN
  G1  = GND
  X2  = USB_HUB_XTAL_OUT
  G2  = GND

H30  HOLE  EMPTY  pkg TH  page 311 : \1\ = NC
R1356  Q_RES  1K 1% CHIP  pkg 0402LF  page 154 : A = RMII_BMC_OCP_RX_ER ; B = GND

(kicad_pcb
	(version 20260206)
	(generator "pcbnew")
	(generator_version "10.0")
	(general
		(thickness 1.6)
		(legacy_teardrops no)
	)
	(paper "A4")
	(title_block
		(title "03242023_DA0F0TMBIJ0_F0T_Motherboard_J_brd_V01_OCP.brd")
		(comment 1 "Grand Teton / footprints 2079-2081 of 6105")
	)
	(layers
		(0 "F.Cu" signal "TOP")
		(4 "In1.Cu" signal "GND")
		(6 "In2.Cu" signal "IN1")
		(8 "In3.Cu" signal "GND1")
		(10 "In4.Cu" signal "IN2")
		(12 "In5.Cu" signal "GND2")
		(14 "In6.Cu" signal "IN3")
		(16 "In7.Cu" signal "GND3")
		(18 "In8.Cu" signal "VCC")
		(20 "In9.Cu" signal "VCC1")
		(22 "In10.Cu" signal "GND4")
		(24 "In11.Cu" signal "IN4")
		(26 "In12.Cu" signal "GND5")
		(28 "In13.Cu" signal "IN5")
		(30 "In14.Cu" signal "GND6")
		(32 "In15.Cu" signal "IN6")
		(34 "In16.Cu" signal "GND7")
		(2 "B.Cu" signal "BOTTOM")
		(9 "F.Adhes" user "F.Adhesive")
		(11 "B.Adhes" user "B.Adhesive")
		(13 "F.Paste" user "Package Geometry/Pastemask Top")
		(15 "B.Paste" user "Package Geometry/Pastemask Bottom")
		(5 "F.SilkS" user "Ref Des/Silkscreen Top")
		(7 "B.SilkS" user "Ref Des/Silkscreen Bottom")
		(1 "F.Mask" user "Board Geometry/Soldermask Top")
		(3 "B.Mask" user "Board Geometry/Soldermask Bottom")
		(17 "Dwgs.User" user "User.Drawings")
		(19 "Cmts.User" user "User.Comments")
		(21 "Eco1.User" user "User.Eco1")
		(23 "Eco2.User" user "User.Eco2")
		(25 "Edge.Cuts" user "Board Geometry/Outline")
		(27 "Margin" user)
		(31 "F.CrtYd" user "Package Geometry/Place Bound Top")
		(29 "B.CrtYd" user "Package Geometry/Place Bound Bottom")
		(35 "F.Fab" user "Ref Des/Assembly Top")
		(33 "B.Fab" user "Ref Des/Assembly Bottom")
	)
	(footprint ""
		(layer "F.Cu")
		(at 7.24916 -99.346766)
		(property "Reference" "Y4"
			(at -1.9558 -2.748788 0)
			(unlocked yes)
			(layer "F.SilkS")
			(effects
				(font
					(size 0.7874 0.5842)
					(thickness 0.1524)
				)
				(justify left)
			)
		)
		(property "Value" ""
			(at 0 0 0)
			(layer "F.Fab")
			(effects
				(font
					(size 1.27 1.27)
				)
			)
		)
		(duplicate_pad_numbers_are_jumpers no)
		(fp_line
			(start -1.2446 -1.4986)
			(end -1.2446 1.4986)
			(stroke
				(width 0.1524)
				(type default)
			)
			(layer "F.SilkS")
		)
		(fp_line
			(start -1.2446 1.4986)
			(end 1.2446 1.4986)
			(stroke
				(width 0.1524)
				(type default)
			)
			(layer "F.SilkS")
		)
		(fp_line
			(start 1.2446 -1.4986)
			(end -1.2446 -1.4986)
			(stroke
				(width 0.1524)
				(type default)
			)
			(layer "F.SilkS")
		)
		(fp_line
			(start 1.2446 1.4986)
			(end 1.2446 -1.4986)
			(stroke
				(width 0.1524)
				(type default)
			)
			(layer "F.SilkS")
		)
		(fp_poly
			(pts
				(xy -2.72288 -1.357884) (xy -1.70688 -0.849884) (xy -2.72288 -0.341884)
			)
			(stroke
				(width 0)
				(type default)
			)
			(fill yes)
			(layer "F.SilkS")
		)
		(fp_line
			(start -1.050036 -1.299972)
			(end -1.050036 1.299972)
			(stroke
				(width 0.1)
				(type default)
			)
			(layer "F.Fab")
		)
		(fp_line
			(start -1.050036 1.299972)
			(end 1.050036 1.299972)
			(stroke
				(width 0.1)
				(type default)
			)
			(layer "F.Fab")
		)
		(fp_line
			(start 1.050036 -1.299972)
			(end -1.050036 -1.299972)
			(stroke
				(width 0.1)
				(type default)
			)
			(layer "F.Fab")
		)
		(fp_line
			(start 1.050036 1.299972)
			(end 1.050036 -1.299972)
			(stroke
				(width 0.1)
				(type default)
			)
			(layer "F.Fab")
		)
		(fp_poly
			(pts
				(xy -2.4638 -1.357884) (xy -2.4638 -0.341884) (xy -1.4478 -0.849884)
			)
			(stroke
				(width 0)
				(type default)
			)
			(fill yes)
			(layer "F.Fab")
		)
		(pad "1" smd rect
			(at -0.649986 -0.849884 180)
			(size 0.9144 1.016)
			(layers "F.Cu" "F.Mask" "F.Paste")
			(net "USB_HUB_XTAL_IN")
		)
		(pad "2" smd rect
			(at -0.649986 0.849884 180)
			(size 0.9144 1.016)
			(layers "F.Cu" "F.Mask" "F.Paste")
			(net "GND")
		)
		(pad "3" smd rect
			(at 0.649986 0.849884 180)
			(size 0.9144 1.016)
			(layers "F.Cu" "F.Mask" "F.Paste")
			(net "USB_HUB_XTAL_OUT")
		)
		(pad "4" smd rect
			(at 0.649986 -0.849884 180)
			(size 0.9144 1.016)
			(layers "F.Cu" "F.Mask" "F.Paste")
			(net "GND")
		)
	)
	(footprint ""
		(layer "F.Cu")
		(at 10.63498 -383.867914)
		(property "Reference" "H30"
			(at -2.6416 -7.392924 0)
			(unlocked yes)
			(layer "F.SilkS")
			(effects
				(font
					(size 0.7874 0.5842)
					(thickness 0.1524)
				)
				(justify left)
			)
		)
		(property "Value" ""
			(at 0 0 0)
			(layer "F.Fab")
			(effects
				(font
					(size 1.27 1.27)
				)
			)
		)
		(duplicate_pad_numbers_are_jumpers no)
		(fp_circle
			(center 0 0)
			(end 2.4003 0)
			(stroke
				(width 0.1524)
				(type default)
			)
			(fill no)
			(layer "F.SilkS")
		)
		(fp_circle
			(center 0 0)
			(end 6.5913 0)
			(stroke
				(width 0.1524)
				(type default)
			)
			(fill no)
			(layer "B.SilkS")
		)
		(fp_circle
			(center 0 0)
			(end 6.5913 0)
			(stroke
				(width 0.1)
				(type default)
			)
			(fill no)
			(layer "B.Fab")
		)
		(fp_circle
			(center 0 0)
			(end 2.4003 0)
			(stroke
				(width 0.1)
				(type default)
			)
			(fill no)
			(layer "F.Fab")
		)
		(pad "" np_thru_hole circle
			(at 0 0)
			(size 3.175 3.175)
			(drill 3.175)
			(layers "*.Cu" "*.Mask")
			(clearance 0.381)
			(thermal_gap 0.381)
		)
		(zone
			(layers "F.Cu" "B.Cu" "In1.Cu" "In2.Cu" "In3.Cu" "In4.Cu" "In5.Cu" "In6.Cu"
				"In7.Cu" "In8.Cu" "In9.Cu" "In10.Cu" "In11.Cu" "In12.Cu" "In13.Cu" "In14.Cu"
				"In15.Cu" "In16.Cu"
			)
			(hatch none 0.5)
			(connect_pads
				(clearance 0)
			)
			(min_thickness 0.25)
			(keepout
				(tracks not_allowed)
				(vias allowed)
				(pads allowed)
				(copperpour not_allowed)
				(footprints allowed)
			)
			(placement
				(enabled no)
				(sheetname "")
			)
			(fill
				(thermal_gap 0.5)
				(thermal_bridge_width 0.5)
				(island_removal_mode 0)
			)
			(polygon
				(pts
					(arc
						(start 12.73048 -383.867914)
						(mid 8.53948 -383.867914)
						(end 12.73048 -383.867914)
					)
				)
			)
		)
	)
	(footprint ""
		(layer "F.Cu")
		(at 166.07028 -21.783548 90)
		(property "Reference" "R1356"
			(at 0 0 90)
			(layer "F.SilkS")
			(hide yes)
			(effects
				(font
					(size 1.27 1.27)
				)
			)
		)
		(property "Value" ""
			(at 0 0 90)
			(layer "F.Fab")
			(effects
				(font
					(size 1.27 1.27)
				)
			)
		)
		(duplicate_pad_numbers_are_jumpers no)
		(fp_line
			(start 0.7874 -0.4064)
			(end 0.7874 0.4064)
			(stroke
				(width 0.1524)
				(type default)
			)
			(layer "F.SilkS")
		)
		(fp_line
			(start -0.7874 -0.4064)
			(end 0.7874 -0.4064)
			(stroke
				(width 0.1524)
				(type default)
			)
			(layer "F.SilkS")
		)
		(fp_line
			(start 0.7874 0.4064)
			(end -0.7874 0.4064)
			(stroke
				(width 0.1524)
				(type default)
			)
			(layer "F.SilkS")
		)
		(fp_line
			(start -0.7874 0.4064)
			(end -0.7874 -0.4064)
			(stroke
				(width 0.1524)
				(type default)
			)
			(layer "F.SilkS")
		)
		(fp_line
			(start -0.12065 -0.305054)
			(end -0.12065 -0.2794)
			(stroke
				(width 0.1)
				(type default)
			)
			(layer "F.Fab")
		)
		(fp_line
			(start -0.67945 -0.305054)
			(end -0.12065 -0.305054)
			(stroke
				(width 0.1)
				(type default)
			)
			(layer "F.Fab")
		)
		(fp_line
			(start 0.67945 -0.3048)
			(end 0.67945 0.3048)
			(stroke
				(width 0.1)
				(type default)
			)
			(layer "F.Fab")
		)
		(fp_line
			(start 0.12065 -0.3048)
			(end 0.67945 -0.3048)
			(stroke
				(width 0.1)
				(type default)
			)
			(layer "F.Fab")
		)
		(fp_line
			(start 0.12065 -0.2794)
			(end 0.12065 -0.3048)
			(stroke
				(width 0.1)
				(type default)
			)
			(layer "F.Fab")
		)
		(fp_line
			(start -0.12065 -0.2794)
			(end 0.12065 -0.2794)
			(stroke
				(width 0.1)
				(type default)
			)
			(layer "F.Fab")
		)
		(fp_line
			(start 0.120396 0.2794)
			(end -0.12065 0.2794)
			(stroke
				(width 0.1)
				(type default)
			)
			(layer "F.Fab")
		)
		(fp_line
			(start -0.12065 0.2794)
			(end -0.12065 0.3048)
			(stroke
				(width 0.1)
				(type default)
			)
			(layer "F.Fab")
		)
		(fp_line
			(start 0.67945 0.3048)
			(end 0.120396 0.3048)
			(stroke
				(width 0.1)
				(type default)
			)
			(layer "F.Fab")
		)
		(fp_line
			(start 0.120396 0.3048)
			(end 0.120396 0.2794)
			(stroke
				(width 0.1)
				(type default)
			)
			(layer "F.Fab")
		)
		(fp_line
			(start -0.12065 0.3048)
			(end -0.67945 0.3048)
			(stroke
				(width 0.1)
				(type default)
			)
			(layer "F.Fab")
		)
		(fp_line
			(start -0.67945 0.3048)
			(end -0.67945 -0.305054)
			(stroke
				(width 0.1)
				(type default)
			)
			(layer "F.Fab")
		)
		(pad "1" smd circle
			(at -0.40005 0 90)
			(size 0 0)
			(layers "F.Cu" "F.Mask" "F.Paste")
			(net "RMII_BMC_OCP_RX_ER")
		)
		(pad "2" smd circle
			(at 0.40005 0 90)
			(size 0 0)
			(layers "F.Cu" "F.Mask" "F.Paste")
			(net "GND")
		)
	)
)
